# ZAIUS-LV CARD-DVT-X01-BOM-X00_20170420_Final.xls.xlsx — POP_GA (bom)
| FOXCONN TECHNOLOGY GROUP |  |  |  |  |  |  |  |  |  |  |  |  |
| BILL OF MATERIAL |  |  |  |  |  |  |  |  |  |  |  |  |
| REV OF  BOM |  | CUSTOMER | Customer |  | CUSTOMER P/N |  | PRODUCT CODE |  | PWA  REV |  | DATE |  |
| Sourcing (Single/Sole/Multi) | Critical Commodity (Y or N) | Component Class (1, 2, other) | Customer PSL (Y or N) | Item Number | Foxconn P/N | Customer P/N | Part Description | Manufacturer  Full Name | Manufacturer  Part Number | Qty | RoHS Status | Location |
